# S9S_MB_2U (Grand Teton) — schematic netlist excerpt (pin names and nets, part order shuffled) for the footprints in the layout excerpt that follows; sources: Cadence DE-HDL packaged netlist, KiCad conversion of 03242023_DA0F0TMBIJ0_F0T_Motherboard_J_brd_V01_OCP.brd

R4644  Q_RES  1K 1% EMPTY  pkg 0402LF  page 167 : A = P3V3_AUX ; B = FM_P2E_BUF2_EQB1

(kicad_pcb
	(version 20260206)
	(generator "pcbnew")
	(generator_version "10.0")
	(general
		(thickness 1.6)
		(legacy_teardrops no)
	)
	(paper "A4")
	(title_block
		(title "03242023_DA0F0TMBIJ0_F0T_Motherboard_J_brd_V01_OCP.brd")
		(comment 1 "Grand Teton / footprints 2348-2348 of 6105")
	)
	(layers
		(0 "F.Cu" signal "TOP")
		(4 "In1.Cu" signal "GND")
		(6 "In2.Cu" signal "IN1")
		(8 "In3.Cu" signal "GND1")
		(10 "In4.Cu" signal "IN2")
		(12 "In5.Cu" signal "GND2")
		(14 "In6.Cu" signal "IN3")
		(16 "In7.Cu" signal "GND3")
		(18 "In8.Cu" signal "VCC")
		(20 "In9.Cu" signal "VCC1")
		(22 "In10.Cu" signal "GND4")
		(24 "In11.Cu" signal "IN4")
		(26 "In12.Cu" signal "GND5")
		(28 "In13.Cu" signal "IN5")
		(30 "In14.Cu" signal "GND6")
		(32 "In15.Cu" signal "IN6")
		(34 "In16.Cu" signal "GND7")
		(2 "B.Cu" signal "BOTTOM")
		(9 "F.Adhes" user "F.Adhesive")
		(11 "B.Adhes" user "B.Adhesive")
		(13 "F.Paste" user "Package Geometry/Pastemask Top")
		(15 "B.Paste" user "Package Geometry/Pastemask Bottom")
		(5 "F.SilkS" user "Ref Des/Silkscreen Top")
		(7 "B.SilkS" user "Ref Des/Silkscreen Bottom")
		(1 "F.Mask" user "Board Geometry/Soldermask Top")
		(3 "B.Mask" user "Board Geometry/Soldermask Bottom")
		(17 "Dwgs.User" user "User.Drawings")
		(19 "Cmts.User" user "User.Comments")
		(21 "Eco1.User" user "User.Eco1")
		(23 "Eco2.User" user "User.Eco2")
		(25 "Edge.Cuts" user "Board Geometry/Outline")
		(27 "Margin" user)
		(31 "F.CrtYd" user "Package Geometry/Place Bound Top")
		(29 "B.CrtYd" user "Package Geometry/Place Bound Bottom")
		(35 "F.Fab" user "Ref Des/Assembly Top")
		(33 "B.Fab" user "Ref Des/Assembly Bottom")
	)
	(footprint ""
		(layer "F.Cu")
		(at 49.375314 -391.078212 180)
		(property "Reference" "R4644"
			(at 0 0 180)
			(layer "F.SilkS")
			(hide yes)
			(effects
				(font
					(size 1.27 1.27)
				)
			)
		)
		(property "Value" ""
			(at 0 0 180)
			(layer "F.Fab")
			(effects
				(font
					(size 1.27 1.27)
				)
			)
		)
		(duplicate_pad_numbers_are_jumpers no)
		(fp_line
			(start 0.7874 0.4064)
			(end -0.7874 0.4064)
			(stroke
				(width 0.1524)
				(type default)
			)
			(layer "F.SilkS")
		)
		(fp_line
			(start 0.7874 -0.4064)
			(end 0.7874 0.4064)
			(stroke
				(width 0.1524)
				(type default)
			)
			(layer "F.SilkS")
		)
		(fp_line
			(start -0.7874 0.4064)
			(end -0.7874 -0.4064)
			(stroke
				(width 0.1524)
				(type default)
			)
			(layer "F.SilkS")
		)
		(fp_line
			(start -0.7874 -0.4064)
			(end 0.7874 -0.4064)
			(stroke
				(width 0.1524)
				(type default)
			)
			(layer "F.SilkS")
		)
		(fp_line
			(start 0.67945 0.3048)
			(end 0.120396 0.3048)
			(stroke
				(width 0.1)
				(type default)
			)
			(layer "F.Fab")
		)
		(fp_line
			(start 0.67945 -0.3048)
			(end 0.67945 0.3048)
			(stroke
				(width 0.1)
				(type default)
			)
			(layer "F.Fab")
		)
		(fp_line
			(start 0.12065 -0.2794)
			(end 0.12065 -0.3048)
			(stroke
				(width 0.1)
				(type default)
			)
			(layer "F.Fab")
		)
		(fp_line
			(start 0.12065 -0.3048)
			(end 0.67945 -0.3048)
			(stroke
				(width 0.1)
				(type default)
			)
			(layer "F.Fab")
		)
		(fp_line
			(start 0.120396 0.3048)
			(end 0.120396 0.2794)
			(stroke
				(width 0.1)
				(type default)
			)
			(layer "F.Fab")
		)
		(fp_line
			(start 0.120396 0.2794)
			(end -0.12065 0.2794)
			(stroke
				(width 0.1)
				(type default)
			)
			(layer "F.Fab")
		)
		(fp_line
			(start -0.12065 0.3048)
			(end -0.67945 0.3048)
			(stroke
				(width 0.1)
				(type default)
			)
			(layer "F.Fab")
		)
		(fp_line
			(start -0.12065 0.2794)
			(end -0.12065 0.3048)
			(stroke
				(width 0.1)
				(type default)
			)
			(layer "F.Fab")
		)
		(fp_line
			(start -0.12065 -0.2794)
			(end 0.12065 -0.2794)
			(stroke
				(width 0.1)
				(type default)
			)
			(layer "F.Fab")
		)
		(fp_line
			(start -0.12065 -0.305054)
			(end -0.12065 -0.2794)
			(stroke
				(width 0.1)
				(type default)
			)
			(layer "F.Fab")
		)
		(fp_line
			(start -0.67945 0.3048)
			(end -0.67945 -0.305054)
			(stroke
				(width 0.1)
				(type default)
			)
			(layer "F.Fab")
		)
		(fp_line
			(start -0.67945 -0.305054)
			(end -0.12065 -0.305054)
			(stroke
				(width 0.1)
				(type default)
			)
			(layer "F.Fab")
		)
		(pad "1" smd circle
			(at -0.40005 0 180)
			(size 0 0)
			(layers "F.Cu" "F.Mask" "F.Paste")
			(net "P3V3_AUX")
		)
		(pad "2" smd circle
			(at 0.40005 0 180)
			(size 0 0)
			(layers "F.Cu" "F.Mask" "F.Paste")
			(net "FM_P2E_BUF2_EQB1")
		)
	)
)
